# S9S_MB_2U (Grand Teton) — schematic netlist excerpt (pin names and nets, part order shuffled) for the footprints in the layout excerpt that follows; sources: Cadence DE-HDL packaged netlist, KiCad conversion of 03242023_DA0F0TMBIJ0_F0T_Motherboard_J_brd_V01_OCP.brd

J1  SCONN288_ADR50017P130CC  SCONN288_ADR50017-P130CC IO  pkg DDR288S_1-1VXB  page 82
  VIN_BULK0  = P12V_S3_AUX_CPU0_NVDIMM
  RFU0  = TP_CHA_CPU0_DIMM1_FRU_0
  VIN_MGMT  = P3V3_AUX
  HSCL  = I3C_SPD_DDRABCD_CPU0_LVC1_SCL_R
  HSDA  = I3C_SPD_DDRABCD_CPU0_LVC1_SDA
  VSS0  = GND
  DQ0_A  = M_A_CPU0_SA_DQ<0>
  VSS1  = GND
  DQ1_A  = M_A_CPU0_SA_DQ<1>
  VSS2  = GND
  DQS0_A_T  = M_A_CPU0_SA_DQS_DP<0>
  DQS0_A_C  = M_A_CPU0_SA_DQS_DN<0>
  VSS3  = GND
  DQ4_A  = M_A_CPU0_SA_DQ<4>
  VSS4  = GND
  DQ5_A  = M_A_CPU0_SA_DQ<5>
  VSS5  = GND
  DQ8_A  = M_A_CPU0_SA_DQ<8>
  VSS6  = GND
  DQ9_A  = M_A_CPU0_SA_DQ<9>
  VSS7  = GND
  DQS1_A_T  = M_A_CPU0_SA_DQS_DP<1>
  DQS1_A_C  = M_A_CPU0_SA_DQS_DN<1>
  VSS8  = GND
  DQ12_A  = M_A_CPU0_SA_DQ<12>
  VSS9  = GND
  DQ13_A  = M_A_CPU0_SA_DQ<13>
  VSS10  = GND
  DQ16_A  = M_A_CPU0_SA_DQ<16>
  VSS11  = GND
  DQ17_A  = M_A_CPU0_SA_DQ<17>
  VSS12  = GND
  DQS2_A_T  = M_A_CPU0_SA_DQS_DP<2>
  DQS2_A_C  = M_A_CPU0_SA_DQS_DN<2>
  VSS13  = GND
  DQ20_A  = M_A_CPU0_SA_DQ<20>
  VSS14  = GND
  DQ21_A  = M_A_CPU0_SA_DQ<21>
  VSS15  = GND
  DQ24_A  = M_A_CPU0_SA_DQ<24>
  VSS16  = GND
  DQ25_A  = M_A_CPU0_SA_DQ<25>
  VSS17  = GND
  DQS3_A_T  = M_A_CPU0_SA_DQS_DP<3>
  DQS3_A_C  = M_A_CPU0_SA_DQS_DN<3>
  VSS18  = GND
  DQ28_A  = M_A_CPU0_SA_DQ<28>
  VSS19  = GND
  DQ29_A  = M_A_CPU0_SA_DQ<29>
  VSS20  = GND
  CB0_A  = M_A_CPU0_SA_CB<0>
  VSS21  = GND
  CB1_A  = M_A_CPU0_SA_CB<1>
  VSS22  = GND
  DQS4_A_T  = M_A_CPU0_SA_DQS_DP<4>
  DQS4_A_C  = M_A_CPU0_SA_DQS_DN<4>
  VSS23  = GND
  CB4_A  = M_A_CPU0_SA_CB<4>
  VSS24  = GND
  CB5_A  = M_A_CPU0_SA_CB<5>
  VSS25  = GND
  ALERT_N  = M_A_CPU0_ALERT_N
  VSS26  = GND
  CS0_A_N  = M_A_CPU0_SA_CS_N<0>
  VSS27  = GND
  CA0_A  = M_A_CPU0_SA_CA<0>
  VSS28  = GND
  CA2_A  = M_A_CPU0_SA_CA<2>
  VSS29  = GND
  CA4_A  = M_A_CPU0_SA_CA<4>
  VSS30  = GND
  CA6_A  = M_A_CPU0_SA_CA<6>
  VSS31  = GND
  PAR_A  = M_A_CPU0_SA_PAR
  VSS32  = GND
  CA0_B  = M_A_CPU0_SB_CA<0>
  VSS33  = GND
  CA2_B  = M_A_CPU0_SB_CA<2>
  VSS34  = GND
  CA4_B  = M_A_CPU0_SB_CA<4>
  VSS35  = GND
  CA6_B  = M_A_CPU0_SB_CA<6>
  VSS36  = GND
  CS0_B_N  = M_A_CPU0_SB_CS_N<0>
  VSS37  = GND
  \lbd||rsp_a_n\  = M_A_CPU0_SA_RSP<0>
  \lbs||rsp_b_n\  = M_A_CPU0_SB_RSP<0>
  VSS38  = GND
  CB4_B  = M_A_CPU0_SB_CB<4>
  VSS39  = GND
  CB5_B  = M_A_CPU0_SB_CB<5>
  VSS40  = GND
  \dqs9_b_t||tdqs9_b_t||dbi4_b_n\  = M_A_CPU0_SB_DQS_DP<9>
  \dqs9_b_c||tdqs9_b_c\  = M_A_CPU0_SB_DQS_DN<9>
  VSS41  = GND
  CB0_B  = M_A_CPU0_SB_CB<0>
  VSS42  = GND
  CB1_B  = M_A_CPU0_SB_CB<1>
  VSS43  = GND
  DQ0_B  = M_A_CPU0_SB_DQ<0>
  VSS44  = GND
  DQ1_B  = M_A_CPU0_SB_DQ<1>
  VSS45  = GND
  DQS0_B_T  = M_A_CPU0_SB_DQS_DP<0>
  DQS0_B_C  = M_A_CPU0_SB_DQS_DN<0>
  VSS46  = GND
  DQ4_B  = M_A_CPU0_SB_DQ<4>
  VSS47  = GND
  DQ5_B  = M_A_CPU0_SB_DQ<5>
  VSS48  = GND
  DQ8_B  = M_A_CPU0_SB_DQ<8>
  VSS49  = GND
  DQ9_B  = M_A_CPU0_SB_DQ<9>
  VSS50  = GND
  DQS1_B_T  = M_A_CPU0_SB_DQS_DP<1>
  DQS1_B_C  = M_A_CPU0_SB_DQS_DN<1>
  VSS51  = GND
  DQ12_B  = M_A_CPU0_SB_DQ<12>
  VSS52  = GND
  DQ13_B  = M_A_CPU0_SB_DQ<13>
  VSS53  = GND
  DQ16_B  = M_A_CPU0_SB_DQ<16>
  VSS54  = GND
  DQ17_B  = M_A_CPU0_SB_DQ<17>
  VSS55  = GND
  DQS2_B_T  = M_A_CPU0_SB_DQS_DP<2>
  DQS2_B_C  = M_A_CPU0_SB_DQS_DN<2>
  VSS56  = GND
  DQ20_B  = M_A_CPU0_SB_DQ<20>
  VSS57  = GND
  DQ21_B  = M_A_CPU0_SB_DQ<21>
  VSS58  = GND
  DQ24_B  = M_A_CPU0_SB_DQ<24>
  VSS59  = GND
  DQ25_B  = M_A_CPU0_SB_DQ<25>
  VSS60  = GND
  DQS3_B_T  = M_A_CPU0_SB_DQS_DP<3>
  DQS3_B_C  = M_A_CPU0_SB_DQS_DN<3>
  VSS61  = GND
  DQ28_B  = M_A_CPU0_SB_DQ<28>
  VSS62  = GND
  DQ29_B  = M_A_CPU0_SB_DQ<29>
  VSS63  = GND
  RFU1  = TP_CHA_CPU0_DIMM1_FRU_1
  VIN_BULK1  = P12V_S3_AUX_CPU0_NVDIMM
  VIN_BULK2  = P12V_S3_AUX_CPU0_NVDIMM
  \pwr_good||fail_n\  = PWRGD_CHA_CPU0_DIMM1
  HSA  = PD_CHA_CPU0_DIMM1_SAA
  RFU2  = TP_CHA_CPU0_DIMM1_FRU_2
  RFU3  = TP_CHA_CPU0_DIMM1_FRU_3
  VSS64  = GND
  DQ2_A  = M_A_CPU0_SA_DQ<2>
  VSS65  = GND
  DQ3_A  = M_A_CPU0_SA_DQ<3>
  VSS66  = GND
  \dqs5_a_c||tdqs5_a_c||dqs5_a_t||tdqs5_a_t\  = M_A_CPU0_SA_DQS_DN<5>
  \dqs5_a_t||tdqs5_a_t\  = M_A_CPU0_SA_DQS_DP<5>
  VSS67  = GND
  DQ6_A  = M_A_CPU0_SA_DQ<6>
  VSS68  = GND
  DQ7_A  = M_A_CPU0_SA_DQ<7>
  VSS69  = GND
  DQ10_A  = M_A_CPU0_SA_DQ<10>
  VSS70  = GND
  DQ11_A  = M_A_CPU0_SA_DQ<11>
  VSS71  = GND
  \dqs6_a_c||tdqs6_a_c||dqs6_a_t||tdqs6_a_t\  = M_A_CPU0_SA_DQS_DN<6>
  \dqs6_a_t||tdqs6_a_t\  = M_A_CPU0_SA_DQS_DP<6>
  VSS72  = GND
  DQ14_A  = M_A_CPU0_SA_DQ<14>
  VSS73  = GND
  DQ15_A  = M_A_CPU0_SA_DQ<15>
  VSS74  = GND
  DQ18_A  = M_A_CPU0_SA_DQ<18>
  VSS75  = GND
  DQ19_A  = M_A_CPU0_SA_DQ<19>
  VSS76  = GND
  \dqs7_a_c||tdqs7_a_c\  = M_A_CPU0_SA_DQS_DN<7>
  \dqs7_a_t||tdqs7_a_t\  = M_A_CPU0_SA_DQS_DP<7>
  VSS77  = GND
  DQ22_A  = M_A_CPU0_SA_DQ<22>
  VSS78  = GND
  DQ23_A  = M_A_CPU0_SA_DQ<23>
  VSS79  = GND
  DQ26_A  = M_A_CPU0_SA_DQ<26>
  VSS80  = GND
  DQ27_A  = M_A_CPU0_SA_DQ<27>
  VSS81  = GND
  \dqs8_a_c||tdqs8_a_c\  = M_A_CPU0_SA_DQS_DN<8>
  \dqs8_a_t||tdqs8_a_t\  = M_A_CPU0_SA_DQS_DP<8>
  VSS82  = GND
  DQ30_A  = M_A_CPU0_SA_DQ<30>
  VSS83  = GND
  DQ31_A  = M_A_CPU0_SA_DQ<31>
  VSS84  = GND
  CB2_A  = M_A_CPU0_SA_CB<2>
  VSS85  = GND
  CB3_A  = M_A_CPU0_SA_CB<3>
  VSS86  = GND
  \dqs9_a_c||tdqs9_a_c\  = M_A_CPU0_SA_DQS_DN<9>
  \dqs9_a_t||tdqs9_a_t\  = M_A_CPU0_SA_DQS_DP<9>
  VSS87  = GND
  CB6_A  = M_A_CPU0_SA_CB<6>
  VSS88  = GND
  CB7_A  = M_A_CPU0_SA_CB<7>
  VSS89  = GND
  RESET_N  = RST_M_AB_CPU0_FPGA_N
  VSS90  = GND
  CS1_A_N  = M_A_CPU0_SA_CS_N<1>
  VSS91  = GND
  CA1_A  = M_A_CPU0_SA_CA<1>
  VSS92  = GND
  CA3_A  = M_A_CPU0_SA_CA<3>
  VSS93  = GND
  CA5_A  = M_A_CPU0_SA_CA<5>
  VSS94  = GND
  CK_T  = M_A_CPU0_CLK_DP<0>
  CK_C  = M_A_CPU0_CLK_DN<0>
  VSS95  = GND
  RFU4  = TP_CHA_CPU0_DIMM1_FRU_4
  CA1_B  = M_A_CPU0_SB_CA<1>
  VSS96  = GND
  CA3_B  = M_A_CPU0_SB_CA<3>
  VSS97  = GND
  CA5_B  = M_A_CPU0_SB_CA<5>
  VSS98  = GND
  PAR_B  = M_A_CPU0_SB_PAR
  VSS99  = GND
  CS1_B_N  = M_A_CPU0_SB_CS_N<1>
  VSS100  = GND
  RFU5  = TP_CHA_CPU0_DIMM1_FRU_5
  RFU6  = TP_CHA_CPU0_DIMM1_FRU_6
  VSS101  = GND
  CB6_B  = M_A_CPU0_SB_CB<6>
  VSS102  = GND
  CB7_B  = M_A_CPU0_SB_CB<7>
  VSS103  = GND
  DQS4_B_C  = M_A_CPU0_SB_DQS_DN<4>
  DQS4_B_T  = M_A_CPU0_SB_DQS_DP<4>
  VSS104  = GND
  CB2_B  = M_A_CPU0_SB_CB<2>
  VSS105  = GND
  CB3_B  = M_A_CPU0_SB_CB<3>
  VSS106  = GND
  DQ2_B  = M_A_CPU0_SB_DQ<2>
  VSS107  = GND
  DQ3_B  = M_A_CPU0_SB_DQ<3>
  VSS108  = GND
  \dqs5_b_c||tdqs5_b_c\  = M_A_CPU0_SB_DQS_DN<5>
  \dqs5_b_t||tdqs5_b_t\  = M_A_CPU0_SB_DQS_DP<5>
  VSS109  = GND
  DQ6_B  = M_A_CPU0_SB_DQ<6>
  VSS110  = GND
  DQ7_B  = M_A_CPU0_SB_DQ<7>
  VSS111  = GND
  DQ10_B  = M_A_CPU0_SB_DQ<10>
  VSS112  = GND
  DQ11_B  = M_A_CPU0_SB_DQ<11>
  VSS113  = GND
  \dqs6_b_c||tdqs6_b_c\  = M_A_CPU0_SB_DQS_DN<6>
  \dqs6_b_t||tdqs6_b_t\  = M_A_CPU0_SB_DQS_DP<6>
  VSS114  = GND
  DQ14_B  = M_A_CPU0_SB_DQ<14>
  VSS115  = GND
  DQ15_B  = M_A_CPU0_SB_DQ<15>
  VSS116  = GND
  DQ18_B  = M_A_CPU0_SB_DQ<18>
  VSS117  = GND
  DQ19_B  = M_A_CPU0_SB_DQ<19>
  VSS118  = GND
  \dqs7_b_c||tdqs7_b_c\  = M_A_CPU0_SB_DQS_DN<7>
  \dqs7_b_t||tdqs7_b_t\  = M_A_CPU0_SB_DQS_DP<7>
  VSS119  = GND
  DQ22_B  = M_A_CPU0_SB_DQ<22>
  VSS120  = GND
  DQ23_B  = M_A_CPU0_SB_DQ<23>
  VSS121  = GND
  DQ26_B  = M_A_CPU0_SB_DQ<26>
  VSS122  = GND
  DQ27_B  = M_A_CPU0_SB_DQ<27>
  VSS123  = GND
  \dqs8_b_c||tdqs8_b_c\  = M_A_CPU0_SB_DQS_DN<8>
  \dqs8_b_t||tdqs8_b_t\  = M_A_CPU0_SB_DQS_DP<8>
  VSS124  = GND
  DQ30_B  = M_A_CPU0_SB_DQ<30>
  VSS125  = GND
  DQ31_B  = M_A_CPU0_SB_DQ<31>
  VSS126  = GND
  G1  = GND
  G2  = GND
  G3  = GND

(kicad_pcb
	(version 20260206)
	(generator "pcbnew")
	(generator_version "10.0")
	(general
		(thickness 1.6)
		(legacy_teardrops no)
	)
	(paper "A4")
	(title_block
		(title "03242023_DA0F0TMBIJ0_F0T_Motherboard_J_brd_V01_OCP.brd")
		(comment 1 "Grand Teton / footprint 1236 of 6105 (J1), pads 92-137 of 291")
	)
	(layers
		(0 "F.Cu" signal "TOP")
		(4 "In1.Cu" signal "GND")
		(6 "In2.Cu" signal "IN1")
		(8 "In3.Cu" signal "GND1")
		(10 "In4.Cu" signal "IN2")
		(12 "In5.Cu" signal "GND2")
		(14 "In6.Cu" signal "IN3")
		(16 "In7.Cu" signal "GND3")
		(18 "In8.Cu" signal "VCC")
		(20 "In9.Cu" signal "VCC1")
		(22 "In10.Cu" signal "GND4")
		(24 "In11.Cu" signal "IN4")
		(26 "In12.Cu" signal "GND5")
		(28 "In13.Cu" signal "IN5")
		(30 "In14.Cu" signal "GND6")
		(32 "In15.Cu" signal "IN6")
		(34 "In16.Cu" signal "GND7")
		(2 "B.Cu" signal "BOTTOM")
		(9 "F.Adhes" user "F.Adhesive")
		(11 "B.Adhes" user "B.Adhesive")
		(13 "F.Paste" user "Package Geometry/Pastemask Top")
		(15 "B.Paste" user "Package Geometry/Pastemask Bottom")
		(5 "F.SilkS" user "Ref Des/Silkscreen Top")
		(7 "B.SilkS" user "Ref Des/Silkscreen Bottom")
		(1 "F.Mask" user "Board Geometry/Soldermask Top")
		(3 "B.Mask" user "Board Geometry/Soldermask Bottom")
		(17 "Dwgs.User" user "User.Drawings")
		(19 "Cmts.User" user "User.Comments")
		(21 "Eco1.User" user "User.Eco1")
		(23 "Eco2.User" user "User.Eco2")
		(25 "Edge.Cuts" user "Board Geometry/Outline")
		(27 "Margin" user)
		(31 "F.CrtYd" user "Package Geometry/Place Bound Top")
		(29 "B.CrtYd" user "Package Geometry/Place Bound Bottom")
		(35 "F.Fab" user "Ref Des/Assembly Top")
		(33 "B.Fab" user "Ref Des/Assembly Bottom")
	)
	(footprint ""
		(layer "F.Cu")
		(at 303.393348 -258.091686)
		(property "Reference" "J1"
			(at -3.683 -81.702148 0)
			(unlocked yes)
			(layer "F.SilkS")
			(effects
				(font
					(size 0.7874 0.5842)
					(thickness 0.1524)
				)
				(justify left)
			)
		)
		(property "Value" ""
			(at 0 0 0)
			(layer "F.Fab")
			(effects
				(font
					(size 1.27 1.27)
				)
			)
		)
		(duplicate_pad_numbers_are_jumpers no)
		(pad "92" smd rect
			(at -2.050034 19.12493 270)
			(size 0.519938 1.4986)
			(layers "F.Cu" "F.Mask" "F.Paste")
			(net "GND")
		)
		(pad "93" smd rect
			(at -2.050034 19.975068 270)
			(size 0.519938 1.4986)
			(layers "F.Cu" "F.Mask" "F.Paste")
			(net "M_A_CPU0_SB_DQS_DP<9>")
		)
		(pad "94" smd rect
			(at -2.050034 20.824952 270)
			(size 0.519938 1.4986)
			(layers "F.Cu" "F.Mask" "F.Paste")
			(net "M_A_CPU0_SB_DQS_DN<9>")
		)
		(pad "95" smd rect
			(at -2.050034 21.67509 270)
			(size 0.519938 1.4986)
			(layers "F.Cu" "F.Mask" "F.Paste")
			(net "GND")
		)
		(pad "96" smd rect
			(at -2.050034 22.524974 270)
			(size 0.519938 1.4986)
			(layers "F.Cu" "F.Mask" "F.Paste")
			(net "M_A_CPU0_SB_CB<0>")
		)
		(pad "97" smd rect
			(at -2.050034 23.375112 270)
			(size 0.519938 1.4986)
			(layers "F.Cu" "F.Mask" "F.Paste")
			(net "GND")
		)
		(pad "98" smd rect
			(at -2.050034 24.224996 270)
			(size 0.519938 1.4986)
			(layers "F.Cu" "F.Mask" "F.Paste")
			(net "M_A_CPU0_SB_CB<1>")
		)
		(pad "99" smd rect
			(at -2.050034 25.07488 270)
			(size 0.519938 1.4986)
			(layers "F.Cu" "F.Mask" "F.Paste")
			(net "GND")
		)
		(pad "100" smd rect
			(at -2.050034 25.925018 270)
			(size 0.519938 1.4986)
			(layers "F.Cu" "F.Mask" "F.Paste")
			(net "M_A_CPU0_SB_DQ<0>")
		)
		(pad "101" smd rect
			(at -2.050034 26.774902 270)
			(size 0.519938 1.4986)
			(layers "F.Cu" "F.Mask" "F.Paste")
			(net "GND")
		)
		(pad "102" smd rect
			(at -2.050034 27.62504 270)
			(size 0.519938 1.4986)
			(layers "F.Cu" "F.Mask" "F.Paste")
			(net "M_A_CPU0_SB_DQ<1>")
		)
		(pad "103" smd rect
			(at -2.050034 28.474924 270)
			(size 0.519938 1.4986)
			(layers "F.Cu" "F.Mask" "F.Paste")
			(net "GND")
		)
		(pad "104" smd rect
			(at -2.050034 29.325062 270)
			(size 0.519938 1.4986)
			(layers "F.Cu" "F.Mask" "F.Paste")
			(net "M_A_CPU0_SB_DQS_DP<0>")
		)
		(pad "105" smd rect
			(at -2.050034 30.174946 270)
			(size 0.519938 1.4986)
			(layers "F.Cu" "F.Mask" "F.Paste")
			(net "M_A_CPU0_SB_DQS_DN<0>")
		)
		(pad "106" smd rect
			(at -2.050034 31.025084 270)
			(size 0.519938 1.4986)
			(layers "F.Cu" "F.Mask" "F.Paste")
			(net "GND")
		)
		(pad "107" smd rect
			(at -2.050034 31.874968 270)
			(size 0.519938 1.4986)
			(layers "F.Cu" "F.Mask" "F.Paste")
			(net "M_A_CPU0_SB_DQ<4>")
		)
		(pad "108" smd rect
			(at -2.050034 32.725106 270)
			(size 0.519938 1.4986)
			(layers "F.Cu" "F.Mask" "F.Paste")
			(net "GND")
		)
		(pad "109" smd rect
			(at -2.050034 33.57499 270)
			(size 0.519938 1.4986)
			(layers "F.Cu" "F.Mask" "F.Paste")
			(net "M_A_CPU0_SB_DQ<5>")
		)
		(pad "110" smd rect
			(at -2.050034 34.425128 270)
			(size 0.519938 1.4986)
			(layers "F.Cu" "F.Mask" "F.Paste")
			(net "GND")
		)
		(pad "111" smd rect
			(at -2.050034 35.275012 270)
			(size 0.519938 1.4986)
			(layers "F.Cu" "F.Mask" "F.Paste")
			(net "M_A_CPU0_SB_DQ<8>")
		)
		(pad "112" smd rect
			(at -2.050034 36.124896 270)
			(size 0.519938 1.4986)
			(layers "F.Cu" "F.Mask" "F.Paste")
			(net "GND")
		)
		(pad "113" smd rect
			(at -2.050034 36.975034 270)
			(size 0.519938 1.4986)
			(layers "F.Cu" "F.Mask" "F.Paste")
			(net "M_A_CPU0_SB_DQ<9>")
		)
		(pad "114" smd rect
			(at -2.050034 37.824918 270)
			(size 0.519938 1.4986)
			(layers "F.Cu" "F.Mask" "F.Paste")
			(net "GND")
		)
		(pad "115" smd rect
			(at -2.050034 38.675056 270)
			(size 0.519938 1.4986)
			(layers "F.Cu" "F.Mask" "F.Paste")
			(net "M_A_CPU0_SB_DQS_DP<1>")
		)
		(pad "116" smd rect
			(at -2.050034 39.52494 270)
			(size 0.519938 1.4986)
			(layers "F.Cu" "F.Mask" "F.Paste")
			(net "M_A_CPU0_SB_DQS_DN<1>")
		)
		(pad "117" smd rect
			(at -2.050034 40.375078 270)
			(size 0.519938 1.4986)
			(layers "F.Cu" "F.Mask" "F.Paste")
			(net "GND")
		)
		(pad "118" smd rect
			(at -2.050034 41.224962 270)
			(size 0.519938 1.4986)
			(layers "F.Cu" "F.Mask" "F.Paste")
			(net "M_A_CPU0_SB_DQ<12>")
		)
		(pad "119" smd rect
			(at -2.050034 42.0751 270)
			(size 0.519938 1.4986)
			(layers "F.Cu" "F.Mask" "F.Paste")
			(net "GND")
		)
		(pad "120" smd rect
			(at -2.050034 42.924984 270)
			(size 0.519938 1.4986)
			(layers "F.Cu" "F.Mask" "F.Paste")
			(net "M_A_CPU0_SB_DQ<13>")
		)
		(pad "121" smd rect
			(at -2.050034 43.775122 270)
			(size 0.519938 1.4986)
			(layers "F.Cu" "F.Mask" "F.Paste")
			(net "GND")
		)
		(pad "122" smd rect
			(at -2.050034 44.625006 270)
			(size 0.519938 1.4986)
			(layers "F.Cu" "F.Mask" "F.Paste")
			(net "M_A_CPU0_SB_DQ<16>")
		)
		(pad "123" smd rect
			(at -2.050034 45.47489 270)
			(size 0.519938 1.4986)
			(layers "F.Cu" "F.Mask" "F.Paste")
			(net "GND")
		)
		(pad "124" smd rect
			(at -2.050034 46.325028 270)
			(size 0.519938 1.4986)
			(layers "F.Cu" "F.Mask" "F.Paste")
			(net "M_A_CPU0_SB_DQ<17>")
		)
		(pad "125" smd rect
			(at -2.050034 47.174912 270)
			(size 0.519938 1.4986)
			(layers "F.Cu" "F.Mask" "F.Paste")
			(net "GND")
		)
		(pad "126" smd rect
			(at -2.050034 48.02505 270)
			(size 0.519938 1.4986)
			(layers "F.Cu" "F.Mask" "F.Paste")
			(net "M_A_CPU0_SB_DQS_DP<2>")
		)
		(pad "127" smd rect
			(at -2.050034 48.874934 270)
			(size 0.519938 1.4986)
			(layers "F.Cu" "F.Mask" "F.Paste")
			(net "M_A_CPU0_SB_DQS_DN<2>")
		)
		(pad "128" smd rect
			(at -2.050034 49.725072 270)
			(size 0.519938 1.4986)
			(layers "F.Cu" "F.Mask" "F.Paste")
			(net "GND")
		)
		(pad "129" smd rect
			(at -2.050034 50.574956 270)
			(size 0.519938 1.4986)
			(layers "F.Cu" "F.Mask" "F.Paste")
			(net "M_A_CPU0_SB_DQ<20>")
		)
		(pad "130" smd rect
			(at -2.050034 51.425094 270)
			(size 0.519938 1.4986)
			(layers "F.Cu" "F.Mask" "F.Paste")
			(net "GND")
		)
		(pad "131" smd rect
			(at -2.050034 52.274978 270)
			(size 0.519938 1.4986)
			(layers "F.Cu" "F.Mask" "F.Paste")
			(net "M_A_CPU0_SB_DQ<21>")
		)
		(pad "132" smd rect
			(at -2.050034 53.125116 270)
			(size 0.519938 1.4986)
			(layers "F.Cu" "F.Mask" "F.Paste")
			(net "GND")
		)
		(pad "133" smd rect
			(at -2.050034 53.975 270)
			(size 0.519938 1.4986)
			(layers "F.Cu" "F.Mask" "F.Paste")
			(net "M_A_CPU0_SB_DQ<24>")
		)
		(pad "134" smd rect
			(at -2.050034 54.824884 270)
			(size 0.519938 1.4986)
			(layers "F.Cu" "F.Mask" "F.Paste")
			(net "GND")
		)
		(pad "135" smd rect
			(at -2.050034 55.675022 270)
			(size 0.519938 1.4986)
			(layers "F.Cu" "F.Mask" "F.Paste")
			(net "M_A_CPU0_SB_DQ<25>")
		)
		(pad "136" smd rect
			(at -2.050034 56.524906 270)
			(size 0.519938 1.4986)
			(layers "F.Cu" "F.Mask" "F.Paste")
			(net "GND")
		)
		(pad "137" smd rect
			(at -2.050034 57.375044 270)
			(size 0.519938 1.4986)
			(layers "F.Cu" "F.Mask" "F.Paste")
			(net "M_A_CPU0_SB_DQS_DP<3>")
		)
	)
)
